(kicad_pcb
	(version 20260206)
	(generator "pcbnew")
	(generator_version "10.0")
	(general
		(thickness 1.6)
		(legacy_teardrops no)
	)
	(paper "A4")
	(title_block
		(title "04192023_DAF0TMB3IC0_F0TG_MB_C_brd_V02_OCP.brd")
		(comment 1 "Grand Teton / footprints 3586-3591 of 8354")
	)
	(layers
		(0 "F.Cu" signal "TOP")
		(4 "In1.Cu" signal "GND")
		(6 "In2.Cu" signal "IN1")
		(8 "In3.Cu" signal "GND1")
		(10 "In4.Cu" signal "IN2")
		(12 "In5.Cu" signal "GND2")
		(14 "In6.Cu" signal "IN3")
		(16 "In7.Cu" signal "GND3")
		(18 "In8.Cu" signal "VCC")
		(20 "In9.Cu" signal "VCC1")
		(22 "In10.Cu" signal "GND4")
		(24 "In11.Cu" signal "IN4")
		(26 "In12.Cu" signal "GND5")
		(28 "In13.Cu" signal "IN5")
		(30 "In14.Cu" signal "GND6")
		(32 "In15.Cu" signal "IN6")
		(34 "In16.Cu" signal "GND7")
		(2 "B.Cu" signal "BOTTOM")
		(9 "F.Adhes" user "F.Adhesive")
		(11 "B.Adhes" user "B.Adhesive")
		(13 "F.Paste" user "Package Geometry/Pastemask Top")
		(15 "B.Paste" user "Package Geometry/Pastemask Bottom")
		(5 "F.SilkS" user "Ref Des/Silkscreen Top")
		(7 "B.SilkS" user "Ref Des/Silkscreen Bottom")
		(1 "F.Mask" user "Board Geometry/Soldermask Top")
		(3 "B.Mask" user "Board Geometry/Soldermask Bottom")
		(17 "Dwgs.User" user "User.Drawings")
		(19 "Cmts.User" user "User.Comments")
		(21 "Eco1.User" user "User.Eco1")
		(23 "Eco2.User" user "User.Eco2")
		(25 "Edge.Cuts" user "Board Geometry/Outline")
		(27 "Margin" user)
		(31 "F.CrtYd" user "Package Geometry/Place Bound Top")
		(29 "B.CrtYd" user "Package Geometry/Place Bound Bottom")
		(35 "F.Fab" user "Ref Des/Assembly Top")
		(33 "B.Fab" user "Ref Des/Assembly Bottom")
	)
	(footprint ""
		(layer "F.Cu")
		(at 252.222 -38.683946 180)
		(property "Reference" "R3978"
			(at 0 0 180)
			(layer "F.SilkS")
			(hide yes)
			(effects
				(font
					(size 1.27 1.27)
				)
			)
		)
		(property "Value" ""
			(at 0 0 180)
			(layer "F.Fab")
			(effects
				(font
					(size 1.27 1.27)
				)
			)
		)
		(duplicate_pad_numbers_are_jumpers no)
		(fp_line
			(start 0.7874 0.4064)
			(end -0.7874 0.4064)
			(stroke
				(width 0.1524)
				(type default)
			)
			(layer "F.SilkS")
		)
		(fp_line
			(start 0.7874 -0.4064)
			(end 0.7874 0.4064)
			(stroke
				(width 0.1524)
				(type default)
			)
			(layer "F.SilkS")
		)
		(fp_line
			(start -0.7874 0.4064)
			(end -0.7874 -0.4064)
			(stroke
				(width 0.1524)
				(type default)
			)
			(layer "F.SilkS")
		)
		(fp_line
			(start -0.7874 -0.4064)
			(end 0.7874 -0.4064)
			(stroke
				(width 0.1524)
				(type default)
			)
			(layer "F.SilkS")
		)
		(fp_line
			(start 0.67945 0.3048)
			(end 0.120396 0.3048)
			(stroke
				(width 0.1)
				(type default)
			)
			(layer "F.Fab")
		)
		(fp_line
			(start 0.67945 -0.3048)
			(end 0.67945 0.3048)
			(stroke
				(width 0.1)
				(type default)
			)
			(layer "F.Fab")
		)
		(fp_line
			(start 0.12065 -0.2794)
			(end 0.12065 -0.3048)
			(stroke
				(width 0.1)
				(type default)
			)
			(layer "F.Fab")
		)
		(fp_line
			(start 0.12065 -0.3048)
			(end 0.67945 -0.3048)
			(stroke
				(width 0.1)
				(type default)
			)
			(layer "F.Fab")
		)
		(fp_line
			(start 0.120396 0.3048)
			(end 0.120396 0.2794)
			(stroke
				(width 0.1)
				(type default)
			)
			(layer "F.Fab")
		)
		(fp_line
			(start 0.120396 0.2794)
			(end -0.12065 0.2794)
			(stroke
				(width 0.1)
				(type default)
			)
			(layer "F.Fab")
		)
		(fp_line
			(start -0.12065 0.3048)
			(end -0.67945 0.3048)
			(stroke
				(width 0.1)
				(type default)
			)
			(layer "F.Fab")
		)
		(fp_line
			(start -0.12065 0.2794)
			(end -0.12065 0.3048)
			(stroke
				(width 0.1)
				(type default)
			)
			(layer "F.Fab")
		)
		(fp_line
			(start -0.12065 -0.2794)
			(end 0.12065 -0.2794)
			(stroke
				(width 0.1)
				(type default)
			)
			(layer "F.Fab")
		)
		(fp_line
			(start -0.12065 -0.305054)
			(end -0.12065 -0.2794)
			(stroke
				(width 0.1)
				(type default)
			)
			(layer "F.Fab")
		)
		(fp_line
			(start -0.67945 0.3048)
			(end -0.67945 -0.305054)
			(stroke
				(width 0.1)
				(type default)
			)
			(layer "F.Fab")
		)
		(fp_line
			(start -0.67945 -0.305054)
			(end -0.12065 -0.305054)
			(stroke
				(width 0.1)
				(type default)
			)
			(layer "F.Fab")
		)
		(pad "1" smd circle
			(at -0.40005 0 180)
			(size 0 0)
			(layers "F.Cu" "F.Mask" "F.Paste")
			(net "P3V3_AUX")
		)
		(pad "2" smd circle
			(at 0.40005 0 180)
			(size 0 0)
			(layers "F.Cu" "F.Mask" "F.Paste")
			(net "HP_LVC3_E1S_0_HSC_PWRGD")
		)
	)
	(footprint ""
		(layer "F.Cu")
		(at 151.182832 -77.752956)
		(property "Reference" "PL6000"
			(at -5.397754 -4.964684 0)
			(unlocked yes)
			(layer "F.SilkS")
			(effects
				(font
					(size 0.7874 0.5842)
					(thickness 0.1524)
				)
				(justify left)
			)
		)
		(property "Value" ""
			(at 0 0 0)
			(layer "F.Fab")
			(effects
				(font
					(size 1.27 1.27)
				)
			)
		)
		(duplicate_pad_numbers_are_jumpers no)
		(fp_line
			(start -3.6576 -3.350006)
			(end 3.64998 -3.350006)
			(stroke
				(width 0.1524)
				(type default)
			)
			(layer "F.SilkS")
		)
		(fp_line
			(start -3.64998 -1.8034)
			(end -3.64998 -3.350006)
			(stroke
				(width 0.1524)
				(type default)
			)
			(layer "F.SilkS")
		)
		(fp_line
			(start -3.64998 3.350006)
			(end -3.64998 1.8288)
			(stroke
				(width 0.1524)
				(type default)
			)
			(layer "F.SilkS")
		)
		(fp_line
			(start 3.64998 -3.350006)
			(end 3.64998 -1.8034)
			(stroke
				(width 0.1524)
				(type default)
			)
			(layer "F.SilkS")
		)
		(fp_line
			(start 3.64998 1.8034)
			(end 3.64998 3.350006)
			(stroke
				(width 0.1524)
				(type default)
			)
			(layer "F.SilkS")
		)
		(fp_line
			(start 3.64998 3.350006)
			(end -3.64998 3.350006)
			(stroke
				(width 0.1524)
				(type default)
			)
			(layer "F.SilkS")
		)
		(fp_line
			(start -3.64998 -3.350006)
			(end 3.64998 -3.350006)
			(stroke
				(width 0.1)
				(type default)
			)
			(layer "F.Fab")
		)
		(fp_line
			(start -3.64998 3.350006)
			(end -3.64998 -3.350006)
			(stroke
				(width 0.1)
				(type default)
			)
			(layer "F.Fab")
		)
		(fp_line
			(start 3.64998 -3.350006)
			(end 3.64998 3.350006)
			(stroke
				(width 0.1)
				(type default)
			)
			(layer "F.Fab")
		)
		(fp_line
			(start 3.64998 3.350006)
			(end -3.64998 3.350006)
			(stroke
				(width 0.1)
				(type default)
			)
			(layer "F.Fab")
		)
		(pad "1" smd rect
			(at -2.92481 0)
			(size 2.15392 3.302)
			(layers "F.Cu" "F.Mask" "F.Paste")
			(net "SW_P1V8_AUX_PH")
		)
		(pad "2" smd rect
			(at 2.92481 0)
			(size 2.15392 3.302)
			(layers "F.Cu" "F.Mask" "F.Paste")
			(net "P1V8_AUX")
		)
	)
	(footprint ""
		(layer "F.Cu")
		(at 130.231642 -71.303134 180)
		(property "Reference" "PC6022"
			(at 0 0 180)
			(layer "F.SilkS")
			(hide yes)
			(effects
				(font
					(size 1.27 1.27)
				)
			)
		)
		(property "Value" ""
			(at 0 0 180)
			(layer "F.Fab")
			(effects
				(font
					(size 1.27 1.27)
				)
			)
		)
		(duplicate_pad_numbers_are_jumpers no)
		(fp_line
			(start 0.7874 0.4064)
			(end -0.7874 0.4064)
			(stroke
				(width 0.1524)
				(type default)
			)
			(layer "F.SilkS")
		)
		(fp_line
			(start 0.7874 -0.4064)
			(end 0.7874 0.4064)
			(stroke
				(width 0.1524)
				(type default)
			)
			(layer "F.SilkS")
		)
		(fp_line
			(start -0.7874 0.4064)
			(end -0.7874 -0.4064)
			(stroke
				(width 0.1524)
				(type default)
			)
			(layer "F.SilkS")
		)
		(fp_line
			(start -0.7874 -0.4064)
			(end 0.7874 -0.4064)
			(stroke
				(width 0.1524)
				(type default)
			)
			(layer "F.SilkS")
		)
		(fp_line
			(start 0.67945 0.3048)
			(end 0.120396 0.3048)
			(stroke
				(width 0.1)
				(type default)
			)
			(layer "F.Fab")
		)
		(fp_line
			(start 0.67945 -0.3048)
			(end 0.67945 0.3048)
			(stroke
				(width 0.1)
				(type default)
			)
			(layer "F.Fab")
		)
		(fp_line
			(start 0.12065 -0.2794)
			(end 0.12065 -0.3048)
			(stroke
				(width 0.1)
				(type default)
			)
			(layer "F.Fab")
		)
		(fp_line
			(start 0.12065 -0.3048)
			(end 0.67945 -0.3048)
			(stroke
				(width 0.1)
				(type default)
			)
			(layer "F.Fab")
		)
		(fp_line
			(start 0.120396 0.3048)
			(end 0.120396 0.2794)
			(stroke
				(width 0.1)
				(type default)
			)
			(layer "F.Fab")
		)
		(fp_line
			(start 0.120396 0.2794)
			(end -0.12065 0.2794)
			(stroke
				(width 0.1)
				(type default)
			)
			(layer "F.Fab")
		)
		(fp_line
			(start -0.12065 0.3048)
			(end -0.67945 0.3048)
			(stroke
				(width 0.1)
				(type default)
			)
			(layer "F.Fab")
		)
		(fp_line
			(start -0.12065 0.2794)
			(end -0.12065 0.3048)
			(stroke
				(width 0.1)
				(type default)
			)
			(layer "F.Fab")
		)
		(fp_line
			(start -0.12065 -0.2794)
			(end 0.12065 -0.2794)
			(stroke
				(width 0.1)
				(type default)
			)
			(layer "F.Fab")
		)
		(fp_line
			(start -0.12065 -0.305054)
			(end -0.12065 -0.2794)
			(stroke
				(width 0.1)
				(type default)
			)
			(layer "F.Fab")
		)
		(fp_line
			(start -0.67945 0.3048)
			(end -0.67945 -0.305054)
			(stroke
				(width 0.1)
				(type default)
			)
			(layer "F.Fab")
		)
		(fp_line
			(start -0.67945 -0.305054)
			(end -0.12065 -0.305054)
			(stroke
				(width 0.1)
				(type default)
			)
			(layer "F.Fab")
		)
		(pad "1" smd circle
			(at -0.40005 0 180)
			(size 0 0)
			(layers "F.Cu" "F.Mask" "F.Paste")
			(net "P1V2_AUX")
		)
		(pad "2" smd circle
			(at 0.40005 0 180)
			(size 0 0)
			(layers "F.Cu" "F.Mask" "F.Paste")
			(net "GND")
		)
	)
	(footprint ""
		(layer "F.Cu")
		(at 360.76001 -417.313618)
		(property "Reference" "R3036"
			(at 0 0 0)
			(layer "F.SilkS")
			(hide yes)
			(effects
				(font
					(size 1.27 1.27)
				)
			)
		)
		(property "Value" ""
			(at 0 0 0)
			(layer "F.Fab")
			(effects
				(font
					(size 1.27 1.27)
				)
			)
		)
		(duplicate_pad_numbers_are_jumpers no)
		(fp_line
			(start -0.7874 -0.4064)
			(end 0.7874 -0.4064)
			(stroke
				(width 0.1524)
				(type default)
			)
			(layer "F.SilkS")
		)
		(fp_line
			(start -0.7874 0.4064)
			(end -0.7874 -0.4064)
			(stroke
				(width 0.1524)
				(type default)
			)
			(layer "F.SilkS")
		)
		(fp_line
			(start 0.7874 -0.4064)
			(end 0.7874 0.4064)
			(stroke
				(width 0.1524)
				(type default)
			)
			(layer "F.SilkS")
		)
		(fp_line
			(start 0.7874 0.4064)
			(end -0.7874 0.4064)
			(stroke
				(width 0.1524)
				(type default)
			)
			(layer "F.SilkS")
		)
		(fp_line
			(start -0.67945 -0.305054)
			(end -0.12065 -0.305054)
			(stroke
				(width 0.1)
				(type default)
			)
			(layer "F.Fab")
		)
		(fp_line
			(start -0.67945 0.3048)
			(end -0.67945 -0.305054)
			(stroke
				(width 0.1)
				(type default)
			)
			(layer "F.Fab")
		)
		(fp_line
			(start -0.12065 -0.305054)
			(end -0.12065 -0.2794)
			(stroke
				(width 0.1)
				(type default)
			)
			(layer "F.Fab")
		)
		(fp_line
			(start -0.12065 -0.2794)
			(end 0.12065 -0.2794)
			(stroke
				(width 0.1)
				(type default)
			)
			(layer "F.Fab")
		)
		(fp_line
			(start -0.12065 0.2794)
			(end -0.12065 0.3048)
			(stroke
				(width 0.1)
				(type default)
			)
			(layer "F.Fab")
		)
		(fp_line
			(start -0.12065 0.3048)
			(end -0.67945 0.3048)
			(stroke
				(width 0.1)
				(type default)
			)
			(layer "F.Fab")
		)
		(fp_line
			(start 0.120396 0.2794)
			(end -0.12065 0.2794)
			(stroke
				(width 0.1)
				(type default)
			)
			(layer "F.Fab")
		)
		(fp_line
			(start 0.120396 0.3048)
			(end 0.120396 0.2794)
			(stroke
				(width 0.1)
				(type default)
			)
			(layer "F.Fab")
		)
		(fp_line
			(start 0.12065 -0.3048)
			(end 0.67945 -0.3048)
			(stroke
				(width 0.1)
				(type default)
			)
			(layer "F.Fab")
		)
		(fp_line
			(start 0.12065 -0.2794)
			(end 0.12065 -0.3048)
			(stroke
				(width 0.1)
				(type default)
			)
			(layer "F.Fab")
		)
		(fp_line
			(start 0.67945 -0.3048)
			(end 0.67945 0.3048)
			(stroke
				(width 0.1)
				(type default)
			)
			(layer "F.Fab")
		)
		(fp_line
			(start 0.67945 0.3048)
			(end 0.120396 0.3048)
			(stroke
				(width 0.1)
				(type default)
			)
			(layer "F.Fab")
		)
		(pad "1" smd circle
			(at -0.40005 0)
			(size 0 0)
			(layers "F.Cu" "F.Mask" "F.Paste")
			(net "UART_BMC_BIC_R_BUF_RX")
		)
		(pad "2" smd circle
			(at 0.40005 0)
			(size 0 0)
			(layers "F.Cu" "F.Mask" "F.Paste")
			(net "UART_BMC_BIC_BUF_RX")
		)
	)
	(footprint ""
		(layer "F.Cu")
		(at 260.99008 -138.848846 180)
		(property "Reference" "U54"
			(at 1.0033 -2.747264 0)
			(unlocked yes)
			(layer "F.SilkS")
			(effects
				(font
					(size 0.7874 0.5842)
					(thickness 0.1524)
				)
				(justify left)
			)
		)
		(property "Value" ""
			(at 0 0 180)
			(layer "F.Fab")
			(effects
				(font
					(size 1.27 1.27)
				)
			)
		)
		(duplicate_pad_numbers_are_jumpers no)
		(fp_line
			(start 1.145286 1.2954)
			(end 1.145286 -1.2954)
			(stroke
				(width 0.1524)
				(type default)
			)
			(layer "F.SilkS")
		)
		(fp_line
			(start 1.145286 -1.2954)
			(end -1.145286 -1.2954)
			(stroke
				(width 0.1524)
				(type default)
			)
			(layer "F.SilkS")
		)
		(fp_line
			(start -1.145286 1.2954)
			(end 1.145286 1.2954)
			(stroke
				(width 0.1524)
				(type default)
			)
			(layer "F.SilkS")
		)
		(fp_line
			(start -1.145286 -1.2954)
			(end -1.145286 1.2954)
			(stroke
				(width 0.1524)
				(type default)
			)
			(layer "F.SilkS")
		)
		(fp_poly
			(pts
				(xy -0.804926 -1.442466) (xy -1.058926 -1.950466) (xy -0.550926 -1.950466)
			)
			(stroke
				(width 0)
				(type default)
			)
			(fill yes)
			(layer "F.SilkS")
		)
		(fp_line
			(start 0.87503 1.02489)
			(end 0.87503 -1.02489)
			(stroke
				(width 0.1)
				(type default)
			)
			(layer "F.Fab")
		)
		(fp_line
			(start 0.87503 -1.02489)
			(end -0.87503 -1.02489)
			(stroke
				(width 0.1)
				(type default)
			)
			(layer "F.Fab")
		)
		(fp_line
			(start -0.87503 1.02489)
			(end 0.87503 1.02489)
			(stroke
				(width 0.1)
				(type default)
			)
			(layer "F.Fab")
		)
		(fp_line
			(start -0.87503 -1.02489)
			(end -0.87503 1.02489)
			(stroke
				(width 0.1)
				(type default)
			)
			(layer "F.Fab")
		)
		(fp_poly
			(pts
				(xy -1.9304 -1.0541) (xy -1.9304 -0.5461) (xy -1.4224 -0.8001)
			)
			(stroke
				(width 0)
				(type default)
			)
			(fill yes)
			(layer "F.Fab")
		)
		(pad "1" smd rect
			(at -0.649986 -0.8001 270)
			(size 0.1778 0.7112)
			(layers "F.Cu" "F.Mask" "F.Paste")
			(net "PVDD18_S5_P0")
		)
		(pad "2" smd rect
			(at -0.649986 -0.40005 270)
			(size 0.1778 0.7112)
			(layers "F.Cu" "F.Mask" "F.Paste")
			(net "SPI_CPU0_R1_D3")
		)
		(pad "3" smd rect
			(at -0.649986 0 270)
			(size 0.1778 0.7112)
			(layers "F.Cu" "F.Mask" "F.Paste")
			(net "SPI_CPU0_R1_D2")
		)
		(pad "4" smd rect
			(at -0.649986 0.40005 270)
			(size 0.1778 0.7112)
			(layers "F.Cu" "F.Mask" "F.Paste")
			(net "SPI_CPU0_R1_D0")
		)
		(pad "5" smd rect
			(at -0.649986 0.8001 270)
			(size 0.1778 0.7112)
			(layers "F.Cu" "F.Mask" "F.Paste")
			(net "SPI_CPU0_R1_D1")
		)
		(pad "6" smd rect
			(at 0 0.8001 180)
			(size 0.1778 0.7112)
			(layers "F.Cu" "F.Mask" "F.Paste")
			(net "GND")
		)
		(pad "7" smd rect
			(at 0.649986 0.8001 270)
			(size 0.1778 0.7112)
			(layers "F.Cu" "F.Mask" "F.Paste")
			(net "SPI_CPU0_LVC3_D1")
		)
		(pad "8" smd rect
			(at 0.649986 0.40005 270)
			(size 0.1778 0.7112)
			(layers "F.Cu" "F.Mask" "F.Paste")
			(net "SPI_CPU0_LVC3_D0")
		)
		(pad "9" smd rect
			(at 0.649986 0 270)
			(size 0.1778 0.7112)
			(layers "F.Cu" "F.Mask" "F.Paste")
			(net "SPI_CPU0_LVC3_D2")
		)
		(pad "10" smd rect
			(at 0.649986 -0.40005 270)
			(size 0.1778 0.7112)
			(layers "F.Cu" "F.Mask" "F.Paste")
			(net "SPI_CPU0_LVC3_D3")
		)
		(pad "11" smd rect
			(at 0.649986 -0.8001 270)
			(size 0.1778 0.7112)
			(layers "F.Cu" "F.Mask" "F.Paste")
			(net "P3V3_AUX")
		)
		(pad "12" smd rect
			(at 0 -0.8001 180)
			(size 0.1778 0.7112)
			(layers "F.Cu" "F.Mask" "F.Paste")
			(net "ROM_LS_EN")
		)
	)
	(footprint ""
		(layer "F.Cu")
		(at 62.559438 -31.887922 90)
		(property "Reference" "R3873"
			(at 0 0 90)
			(layer "F.SilkS")
			(hide yes)
			(effects
				(font
					(size 1.27 1.27)
				)
			)
		)
		(property "Value" ""
			(at 0 0 90)
			(layer "F.Fab")
			(effects
				(font
					(size 1.27 1.27)
				)
			)
		)
		(duplicate_pad_numbers_are_jumpers no)
		(fp_line
			(start 0.7874 -0.4064)
			(end 0.7874 0.4064)
			(stroke
				(width 0.1524)
				(type default)
			)
			(layer "F.SilkS")
		)
		(fp_line
			(start -0.7874 -0.4064)
			(end 0.7874 -0.4064)
			(stroke
				(width 0.1524)
				(type default)
			)
			(layer "F.SilkS")
		)
		(fp_line
			(start 0.7874 0.4064)
			(end -0.7874 0.4064)
			(stroke
				(width 0.1524)
				(type default)
			)
			(layer "F.SilkS")
		)
		(fp_line
			(start -0.7874 0.4064)
			(end -0.7874 -0.4064)
			(stroke
				(width 0.1524)
				(type default)
			)
			(layer "F.SilkS")
		)
		(fp_line
			(start -0.12065 -0.305054)
			(end -0.12065 -0.2794)
			(stroke
				(width 0.1)
				(type default)
			)
			(layer "F.Fab")
		)
		(fp_line
			(start -0.67945 -0.305054)
			(end -0.12065 -0.305054)
			(stroke
				(width 0.1)
				(type default)
			)
			(layer "F.Fab")
		)
		(fp_line
			(start 0.67945 -0.3048)
			(end 0.67945 0.3048)
			(stroke
				(width 0.1)
				(type default)
			)
			(layer "F.Fab")
		)
		(fp_line
			(start 0.12065 -0.3048)
			(end 0.67945 -0.3048)
			(stroke
				(width 0.1)
				(type default)
			)
			(layer "F.Fab")
		)
		(fp_line
			(start 0.12065 -0.2794)
			(end 0.12065 -0.3048)
			(stroke
				(width 0.1)
				(type default)
			)
			(layer "F.Fab")
		)
		(fp_line
			(start -0.12065 -0.2794)
			(end 0.12065 -0.2794)
			(stroke
				(width 0.1)
				(type default)
			)
			(layer "F.Fab")
		)
		(fp_line
			(start 0.120396 0.2794)
			(end -0.12065 0.2794)
			(stroke
				(width 0.1)
				(type default)
			)
			(layer "F.Fab")
		)
		(fp_line
			(start -0.12065 0.2794)
			(end -0.12065 0.3048)
			(stroke
				(width 0.1)
				(type default)
			)
			(layer "F.Fab")
		)
		(fp_line
			(start 0.67945 0.3048)
			(end 0.120396 0.3048)
			(stroke
				(width 0.1)
				(type default)
			)
			(layer "F.Fab")
		)
		(fp_line
			(start 0.120396 0.3048)
			(end 0.120396 0.2794)
			(stroke
				(width 0.1)
				(type default)
			)
			(layer "F.Fab")
		)
		(fp_line
			(start -0.12065 0.3048)
			(end -0.67945 0.3048)
			(stroke
				(width 0.1)
				(type default)
			)
			(layer "F.Fab")
		)
		(fp_line
			(start -0.67945 0.3048)
			(end -0.67945 -0.305054)
			(stroke
				(width 0.1)
				(type default)
			)
			(layer "F.Fab")
		)
		(pad "1" smd circle
			(at -0.40005 0 90)
			(size 0 0)
			(layers "F.Cu" "F.Mask" "F.Paste")
			(net "P12V_OCP_IMON_2")
		)
		(pad "2" smd circle
			(at 0.40005 0 90)
			(size 0 0)
			(layers "F.Cu" "F.Mask" "F.Paste")
			(net "P12V_OCP_V3_2_ISENSE_MPS_MAM")
		)
	)
)
